FILE_TYPE = MULTI_PHYS_TABLE;

PART 'MP5990GMA1111Z'

{========================================================================================}
:VALUE              | PART_TYPE | MATERIAL | PART_NUMBER    = STANDARD    | LIFECYCLE          | PART_NUMBER   | JEDEC_TYPE          | DESCRIPTION                               | MANUFTR | MANUF_PN           | RD_CMPLS_LVL | CMPLS_LVL | FROM_PJ     | CLASS | DIP_SMD | DATA                            | EE_CHECK_LIST | FP_ECN | PSL | CREATOR | STATUS | MSD | ESD_CDM | ESD_HBM | ESD_MM | PIN_LENGTH_SHORT_PIN | PIN_LENGTH_LONG_PIN | CREATEDAY  ;
{========================================================================================}
 'MP5990GMA-1111-Z' | 'SMLF'    | 'IC'     | 'AL005990A03'(!) = ''          | ''                 | 'AL005990A03' |'LGA45_TH_0-45_7X5'| 'IC(45P)MP5990GMA-1111-Z(LGA)'            | 'MPS'   | 'MP5990GMA-1111-Z' | 'EP(V1)'     | ''        | 'F0T-WILL'  | 'IC'  | ''      | 'MPS_MP5990GMA-1111-Z.pdf'      | ''            | ''     | ''  | ''      | ''     | ''  | ''      | ''      | ''     | '0 MILS'             | '0 MILS'            | '20211122'
 'MP5990GMA-1111-Z' | 'SMLF'    | 'EMPTY'  | 'AL005990A03'(!) = ''          | ''                 | 'AL005990A03' |'LGA45_TH_0-45_7X5'| 'IC(45P)MP5990GMA-1111-Z(LGA)'            | 'MPS'   | 'MP5990GMA-1111-Z' | 'EP(V1)'     | ''        | 'F0T-WILL'  | 'IC'  | ''      | 'MPS_MP5990GMA-1111-Z.pdf'      | ''            | ''     | ''  | ''      | ''     | ''  | ''      | ''      | ''     | '0 MILS'             | '0 MILS'            | '20211122'
 'MP5990GMA-1111-Z' | 'SMLF'    | 'IC'     | 'AR0F0TP4023'(!) = ''               | ''               | 'AR0F0TP4023' |'LGA45_TH_0-45_7X5'| 'PROG IC(45P)MP5990GMA-1111-Z(F9C2)(LGA)' | 'MPS'   | 'MP5990GMA-1111-Z' | 'EP(V1)'     | 'EP(V1)'  | 'F0TG-CART' | 'IC'  | ''      | 'MPS_MP5990GMA-1111-Z_F9C2.pdf' | ''            | ''     | ''  | ''      | ''     | ''  | ''      | ''      | ''     | '0 MILS'             | '0 MILS'            | '20221011'
 'MP5990GMA-1111-Z' | 'SMLF'    | 'EMPTY'  | 'AR0F0TP4023'(!) = ''               | ''               | 'AR0F0TP4023' |'LGA45_TH_0-45_7X5'| 'PROG IC(45P)MP5990GMA-1111-Z(F9C2)(LGA)' | 'MPS'   | 'MP5990GMA-1111-Z' | 'EP(V1)'     | 'EP(V1)'  | 'F0TG-CART' | 'IC'  | ''      | 'MPS_MP5990GMA-1111-Z_F9C2.pdf' | ''            | ''     | ''  | ''      | ''     | ''  | ''      | ''      | ''     | '0 MILS'             | '0 MILS'            | '20221011'

END_PART

END.

